(kicad_pcb
	(version 20260206)
	(generator "pcbnew")
	(generator_version "10.0")
	(general
		(thickness 1.6)
		(legacy_teardrops no)
	)
	(paper "A4")
	(title_block
		(title "Bryce Canyon_IOM_M2_16342-2_OCP.brd")
		(comment 1 "Bryce Canyon / footprints 441-447 of 1146")
	)
	(layers
		(0 "F.Cu" signal "TOP")
		(4 "In1.Cu" signal "L2GND")
		(6 "In2.Cu" signal "L3")
		(8 "In3.Cu" signal "L4VCC")
		(10 "In4.Cu" signal "L5VCC")
		(12 "In5.Cu" signal "L6")
		(14 "In6.Cu" signal "L7GND")
		(2 "B.Cu" signal "BOTTOM")
		(9 "F.Adhes" user "F.Adhesive")
		(11 "B.Adhes" user "B.Adhesive")
		(13 "F.Paste" user "Package Geometry/Pastemask Top")
		(15 "B.Paste" user "Package Geometry/Pastemask Bottom")
		(5 "F.SilkS" user "Ref Des/Silkscreen Top")
		(7 "B.SilkS" user "Ref Des/Silkscreen Bottom")
		(1 "F.Mask" user "Board Geometry/Soldermask Top")
		(3 "B.Mask" user "Board Geometry/Soldermask Bottom")
		(17 "Dwgs.User" user "User.Drawings")
		(19 "Cmts.User" user "User.Comments")
		(21 "Eco1.User" user "User.Eco1")
		(23 "Eco2.User" user "User.Eco2")
		(25 "Edge.Cuts" user "Board Geometry/Outline")
		(27 "Margin" user)
		(31 "F.CrtYd" user "Package Geometry/Place Bound Top")
		(29 "B.CrtYd" user "Package Geometry/Place Bound Bottom")
		(35 "F.Fab" user "Ref Des/Assembly Top")
		(33 "B.Fab" user "Ref Des/Assembly Bottom")
	)
	(footprint ""
		(layer "F.Cu")
		(at 79.231744 -153.745184 180)
		(property "Reference" "R536"
			(at 0 0 180)
			(layer "F.SilkS")
			(hide yes)
			(effects
				(font
					(size 1.27 1.27)
				)
			)
		)
		(property "Value" "0R5J-5-GP"
			(at 0 -8.9535 180)
			(unlocked yes)
			(layer "F.Fab")
			(hide yes)
			(effects
				(font
					(size 1.27 1.016)
					(thickness 0.1524)
				)
			)
		)
		(property "Device Type" "R805H24"
			(at 0 -10.6299 180)
			(unlocked yes)
			(layer "F.Fab")
			(hide yes)
			(effects
				(font
					(size 1.27 1.016)
					(thickness 0.1524)
				)
			)
		)
		(duplicate_pad_numbers_are_jumpers no)
		(fp_line
			(start 0.889 1.7018)
			(end 0.889 -0.508)
			(stroke
				(width 0.1524)
				(type default)
			)
			(layer "F.SilkS")
		)
		(fp_line
			(start 0.889 -1.7018)
			(end 0.889 -0.381)
			(stroke
				(width 0.1524)
				(type default)
			)
			(layer "F.SilkS")
		)
		(fp_line
			(start 0.889 -1.7018)
			(end -0.889 -1.7018)
			(stroke
				(width 0.1524)
				(type default)
			)
			(layer "F.SilkS")
		)
		(fp_line
			(start -0.889 1.7018)
			(end 0.889 1.7018)
			(stroke
				(width 0.1524)
				(type default)
			)
			(layer "F.SilkS")
		)
		(fp_line
			(start -0.889 0.0762)
			(end -0.889 1.7018)
			(stroke
				(width 0.1524)
				(type default)
			)
			(layer "F.SilkS")
		)
		(fp_line
			(start -0.889 -1.7018)
			(end -0.889 0.2794)
			(stroke
				(width 0.1524)
				(type default)
			)
			(layer "F.SilkS")
		)
		(fp_poly
			(pts
				(xy 0.9652 -1.778) (xy 0.9652 1.778) (xy -0.9652 1.778) (xy -0.9652 -1.778)
			)
			(stroke
				(width 0)
				(type default)
			)
			(fill no)
			(layer "F.CrtYd")
		)
		(fp_rect
			(start -0.9652 1.778)
			(end 0.9652 -1.778)
			(stroke
				(width 0)
				(type default)
			)
			(fill no)
			(layer "F.Fab")
		)
		(pad "1" smd rect
			(at 0 -0.9652 180)
			(size 1.397 1.143)
			(layers "F.Cu" "F.Mask" "F.Paste")
			(net "P1V15_STBY")
		)
		(pad "2" smd rect
			(at 0 0.9652 180)
			(size 1.397 1.143)
			(layers "F.Cu" "F.Mask" "F.Paste")
			(net "TPS74801_P1V15_STBY_OUT")
		)
	)
	(footprint ""
		(layer "F.Cu")
		(at 25.6794 -130.4544 180)
		(property "Reference" "R231"
			(at 0 0 180)
			(layer "F.SilkS")
			(hide yes)
			(effects
				(font
					(size 1.27 1.27)
				)
			)
		)
		(property "Value" "120R2F-GP"
			(at 0.064008 -3.993896 180)
			(unlocked yes)
			(layer "F.Fab")
			(hide yes)
			(effects
				(font
					(size 1.016 1.016)
					(thickness 0.1524)
				)
			)
		)
		(property "Device Type" "R402H16"
			(at 0.064008 -5.517896 180)
			(unlocked yes)
			(layer "F.Fab")
			(hide yes)
			(effects
				(font
					(size 1.016 1.016)
					(thickness 0.1524)
				)
			)
		)
		(duplicate_pad_numbers_are_jumpers no)
		(fp_line
			(start 0.508 -0.9398)
			(end -0.508 -0.9398)
			(stroke
				(width 0.1524)
				(type default)
			)
			(layer "F.SilkS")
		)
		(fp_line
			(start -0.508 -0.9398)
			(end -0.508 0.9398)
			(stroke
				(width 0.1524)
				(type default)
			)
			(layer "F.SilkS")
		)
		(fp_rect
			(start -0.508 0.9398)
			(end 0.508 -0.9398)
			(stroke
				(width 0)
				(type default)
			)
			(fill no)
			(layer "F.CrtYd")
		)
		(fp_rect
			(start -0.508 0.9398)
			(end 0.508 -0.9398)
			(stroke
				(width 0)
				(type default)
			)
			(fill no)
			(layer "F.Fab")
		)
		(pad "1" smd custom
			(at 0 -0.4445 180)
			(size 0.1397 0.1397)
			(layers "F.Cu" "F.Mask" "F.Paste")
			(net "GND")
			(options
				(clearance outline)
				(anchor circle)
			)
			(primitives
				(gr_poly
					(pts
						(arc
							(start -0.1778 -0.2794)
							(mid -0.249642 -0.249642)
							(end -0.2794 -0.1778)
						)
						(arc
							(start -0.2794 0.1778)
							(mid -0.249642 0.249642)
							(end -0.1778 0.2794)
						)
						(arc
							(start 0.1778 0.2794)
							(mid 0.249642 0.249642)
							(end 0.2794 0.1778)
						)
						(arc
							(start 0.2794 -0.1778)
							(mid 0.249642 -0.249642)
							(end 0.1778 -0.2794)
						)
					)
					(width 0)
					(fill yes)
				)
			)
		)
		(pad "2" smd custom
			(at 0 0.4445 180)
			(size 0.1397 0.1397)
			(layers "F.Cu" "F.Mask" "F.Paste")
			(net "MEMBA_1")
			(options
				(clearance outline)
				(anchor circle)
			)
			(primitives
				(gr_poly
					(pts
						(arc
							(start -0.1778 -0.2794)
							(mid -0.249642 -0.249642)
							(end -0.2794 -0.1778)
						)
						(arc
							(start -0.2794 0.1778)
							(mid -0.249642 0.249642)
							(end -0.1778 0.2794)
						)
						(arc
							(start 0.1778 0.2794)
							(mid 0.249642 0.249642)
							(end 0.2794 0.1778)
						)
						(arc
							(start 0.2794 -0.1778)
							(mid 0.249642 -0.249642)
							(end 0.1778 -0.2794)
						)
					)
					(width 0)
					(fill yes)
				)
			)
		)
	)
	(footprint ""
		(layer "F.Cu")
		(at 74.426572 -173.774862 -90)
		(property "Reference" "R505"
			(at 0 0 270)
			(layer "F.SilkS")
			(hide yes)
			(effects
				(font
					(size 1.27 1.27)
				)
			)
		)
		(property "Value" "3K57R2F-GP"
			(at 0.064008 -3.993896 270)
			(unlocked yes)
			(layer "F.Fab")
			(hide yes)
			(effects
				(font
					(size 1.016 1.016)
					(thickness 0.1524)
				)
			)
		)
		(property "Device Type" "R402H16"
			(at 0.064008 -5.517896 270)
			(unlocked yes)
			(layer "F.Fab")
			(hide yes)
			(effects
				(font
					(size 1.016 1.016)
					(thickness 0.1524)
				)
			)
		)
		(duplicate_pad_numbers_are_jumpers no)
		(fp_line
			(start -0.508 -0.9398)
			(end -0.508 0.9398)
			(stroke
				(width 0.1524)
				(type default)
			)
			(layer "F.SilkS")
		)
		(fp_line
			(start 0.508 -0.9398)
			(end -0.508 -0.9398)
			(stroke
				(width 0.1524)
				(type default)
			)
			(layer "F.SilkS")
		)
		(fp_rect
			(start -0.508 0.9398)
			(end 0.508 -0.9398)
			(stroke
				(width 0)
				(type default)
			)
			(fill no)
			(layer "F.CrtYd")
		)
		(fp_rect
			(start -0.508 0.9398)
			(end 0.508 -0.9398)
			(stroke
				(width 0)
				(type default)
			)
			(fill no)
			(layer "F.Fab")
		)
		(pad "1" smd custom
			(at 0 -0.4445 270)
			(size 0.1397 0.1397)
			(layers "F.Cu" "F.Mask" "F.Paste")
			(net "TPS74801_P2V5_STBY_OUT")
			(options
				(clearance outline)
				(anchor circle)
			)
			(primitives
				(gr_poly
					(pts
						(arc
							(start -0.1778 -0.2794)
							(mid -0.249642 -0.249642)
							(end -0.2794 -0.1778)
						)
						(arc
							(start -0.2794 0.1778)
							(mid -0.249642 0.249642)
							(end -0.1778 0.2794)
						)
						(arc
							(start 0.1778 0.2794)
							(mid 0.249642 0.249642)
							(end 0.2794 0.1778)
						)
						(arc
							(start 0.2794 -0.1778)
							(mid 0.249642 -0.249642)
							(end 0.1778 -0.2794)
						)
					)
					(width 0)
					(fill yes)
				)
			)
		)
		(pad "2" smd custom
			(at 0 0.4445 270)
			(size 0.1397 0.1397)
			(layers "F.Cu" "F.Mask" "F.Paste")
			(net "TPS74801_P2V5_STBY_FB")
			(options
				(clearance outline)
				(anchor circle)
			)
			(primitives
				(gr_poly
					(pts
						(arc
							(start -0.1778 -0.2794)
							(mid -0.249642 -0.249642)
							(end -0.2794 -0.1778)
						)
						(arc
							(start -0.2794 0.1778)
							(mid -0.249642 0.249642)
							(end -0.1778 0.2794)
						)
						(arc
							(start 0.1778 0.2794)
							(mid 0.249642 0.249642)
							(end 0.2794 0.1778)
						)
						(arc
							(start 0.2794 -0.1778)
							(mid 0.249642 -0.249642)
							(end 0.1778 -0.2794)
						)
					)
					(width 0)
					(fill yes)
				)
			)
		)
	)
	(footprint ""
		(layer "F.Cu")
		(at 98.3234 -173.7106 -90)
		(property "Reference" "R124"
			(at 0 0 270)
			(layer "F.SilkS")
			(hide yes)
			(effects
				(font
					(size 1.27 1.27)
				)
			)
		)
		(property "Value" "0R2J-2-GP"
			(at 0.064008 -3.993896 270)
			(unlocked yes)
			(layer "F.Fab")
			(hide yes)
			(effects
				(font
					(size 1.016 1.016)
					(thickness 0.1524)
				)
			)
		)
		(property "Device Type" "R402H16"
			(at 0.064008 -5.517896 270)
			(unlocked yes)
			(layer "F.Fab")
			(hide yes)
			(effects
				(font
					(size 1.016 1.016)
					(thickness 0.1524)
				)
			)
		)
		(duplicate_pad_numbers_are_jumpers no)
		(fp_line
			(start -0.508 -0.9398)
			(end -0.508 0.9398)
			(stroke
				(width 0.1524)
				(type default)
			)
			(layer "F.SilkS")
		)
		(fp_line
			(start 0.508 -0.9398)
			(end -0.508 -0.9398)
			(stroke
				(width 0.1524)
				(type default)
			)
			(layer "F.SilkS")
		)
		(fp_rect
			(start -0.508 0.9398)
			(end 0.508 -0.9398)
			(stroke
				(width 0)
				(type default)
			)
			(fill no)
			(layer "F.CrtYd")
		)
		(fp_rect
			(start -0.508 0.9398)
			(end 0.508 -0.9398)
			(stroke
				(width 0)
				(type default)
			)
			(fill no)
			(layer "F.Fab")
		)
		(pad "1" smd custom
			(at 0 -0.4445 270)
			(size 0.1397 0.1397)
			(layers "F.Cu" "F.Mask" "F.Paste")
			(net "I2C_DPB_MISC_SCL")
			(options
				(clearance outline)
				(anchor circle)
			)
			(primitives
				(gr_poly
					(pts
						(arc
							(start -0.1778 -0.2794)
							(mid -0.249642 -0.249642)
							(end -0.2794 -0.1778)
						)
						(arc
							(start -0.2794 0.1778)
							(mid -0.249642 0.249642)
							(end -0.1778 0.2794)
						)
						(arc
							(start 0.1778 0.2794)
							(mid 0.249642 0.249642)
							(end 0.2794 0.1778)
						)
						(arc
							(start 0.2794 -0.1778)
							(mid 0.249642 -0.249642)
							(end 0.1778 -0.2794)
						)
					)
					(width 0)
					(fill yes)
				)
			)
		)
		(pad "2" smd custom
			(at 0 0.4445 270)
			(size 0.1397 0.1397)
			(layers "F.Cu" "F.Mask" "F.Paste")
			(net "I2C_DPB_MISC_SCL_R")
			(options
				(clearance outline)
				(anchor circle)
			)
			(primitives
				(gr_poly
					(pts
						(arc
							(start -0.1778 -0.2794)
							(mid -0.249642 -0.249642)
							(end -0.2794 -0.1778)
						)
						(arc
							(start -0.2794 0.1778)
							(mid -0.249642 0.249642)
							(end -0.1778 0.2794)
						)
						(arc
							(start 0.1778 0.2794)
							(mid 0.249642 0.249642)
							(end 0.2794 0.1778)
						)
						(arc
							(start 0.2794 -0.1778)
							(mid 0.249642 -0.249642)
							(end 0.1778 -0.2794)
						)
					)
					(width 0)
					(fill yes)
				)
			)
		)
	)
	(footprint ""
		(layer "F.Cu")
		(at 61.101732 -147.74926 -90)
		(property "Reference" "R166"
			(at 0 0 270)
			(layer "F.SilkS")
			(hide yes)
			(effects
				(font
					(size 1.27 1.27)
				)
			)
		)
		(property "Value" "0R2J-2-GP"
			(at 0.064008 -3.993896 270)
			(unlocked yes)
			(layer "F.Fab")
			(hide yes)
			(effects
				(font
					(size 1.016 1.016)
					(thickness 0.1524)
				)
			)
		)
		(property "Device Type" "R402H16"
			(at 0.064008 -5.517896 270)
			(unlocked yes)
			(layer "F.Fab")
			(hide yes)
			(effects
				(font
					(size 1.016 1.016)
					(thickness 0.1524)
				)
			)
		)
		(duplicate_pad_numbers_are_jumpers no)
		(fp_line
			(start -0.508 -0.9398)
			(end -0.508 0.9398)
			(stroke
				(width 0.1524)
				(type default)
			)
			(layer "F.SilkS")
		)
		(fp_line
			(start 0.508 -0.9398)
			(end -0.508 -0.9398)
			(stroke
				(width 0.1524)
				(type default)
			)
			(layer "F.SilkS")
		)
		(fp_rect
			(start -0.508 0.9398)
			(end 0.508 -0.9398)
			(stroke
				(width 0)
				(type default)
			)
			(fill no)
			(layer "F.CrtYd")
		)
		(fp_rect
			(start -0.508 0.9398)
			(end 0.508 -0.9398)
			(stroke
				(width 0)
				(type default)
			)
			(fill no)
			(layer "F.Fab")
		)
		(pad "1" smd custom
			(at 0 -0.4445 270)
			(size 0.1397 0.1397)
			(layers "F.Cu" "F.Mask" "F.Paste")
			(net "I2C_BMC_COMP_SDA_OUT")
			(options
				(clearance outline)
				(anchor circle)
			)
			(primitives
				(gr_poly
					(pts
						(arc
							(start -0.1778 -0.2794)
							(mid -0.249642 -0.249642)
							(end -0.2794 -0.1778)
						)
						(arc
							(start -0.2794 0.1778)
							(mid -0.249642 0.249642)
							(end -0.1778 0.2794)
						)
						(arc
							(start 0.1778 0.2794)
							(mid 0.249642 0.249642)
							(end 0.2794 0.1778)
						)
						(arc
							(start 0.2794 -0.1778)
							(mid 0.249642 -0.249642)
							(end 0.1778 -0.2794)
						)
					)
					(width 0)
					(fill yes)
				)
			)
		)
		(pad "2" smd custom
			(at 0 0.4445 270)
			(size 0.1397 0.1397)
			(layers "F.Cu" "F.Mask" "F.Paste")
			(net "BMC_SMB4_DAT")
			(options
				(clearance outline)
				(anchor circle)
			)
			(primitives
				(gr_poly
					(pts
						(arc
							(start -0.1778 -0.2794)
							(mid -0.249642 -0.249642)
							(end -0.2794 -0.1778)
						)
						(arc
							(start -0.2794 0.1778)
							(mid -0.249642 0.249642)
							(end -0.1778 0.2794)
						)
						(arc
							(start 0.1778 0.2794)
							(mid 0.249642 0.249642)
							(end 0.2794 0.1778)
						)
						(arc
							(start 0.2794 -0.1778)
							(mid 0.249642 -0.249642)
							(end 0.1778 -0.2794)
						)
					)
					(width 0)
					(fill yes)
				)
			)
		)
	)
	(footprint ""
		(layer "F.Cu")
		(at 178.6382 -5.969)
		(property "Reference" "R528"
			(at 0 0 0)
			(layer "F.SilkS")
			(hide yes)
			(effects
				(font
					(size 1.27 1.27)
				)
			)
		)
		(property "Value" "0R2J-2-GP"
			(at 0.064008 -3.993896 0)
			(unlocked yes)
			(layer "F.Fab")
			(hide yes)
			(effects
				(font
					(size 1.016 1.016)
					(thickness 0.1524)
				)
			)
		)
		(property "Device Type" "R402H16"
			(at 0.064008 -5.517896 0)
			(unlocked yes)
			(layer "F.Fab")
			(hide yes)
			(effects
				(font
					(size 1.016 1.016)
					(thickness 0.1524)
				)
			)
		)
		(duplicate_pad_numbers_are_jumpers no)
		(fp_line
			(start -0.508 -0.9398)
			(end -0.508 0.9398)
			(stroke
				(width 0.1524)
				(type default)
			)
			(layer "F.SilkS")
		)
		(fp_line
			(start 0.508 -0.9398)
			(end -0.508 -0.9398)
			(stroke
				(width 0.1524)
				(type default)
			)
			(layer "F.SilkS")
		)
		(fp_rect
			(start -0.508 0.9398)
			(end 0.508 -0.9398)
			(stroke
				(width 0)
				(type default)
			)
			(fill no)
			(layer "F.CrtYd")
		)
		(fp_rect
			(start -0.508 0.9398)
			(end 0.508 -0.9398)
			(stroke
				(width 0)
				(type default)
			)
			(fill no)
			(layer "F.Fab")
		)
		(pad "1" smd custom
			(at 0 -0.4445)
			(size 0.1397 0.1397)
			(layers "F.Cu" "F.Mask" "F.Paste")
			(net "BMC_ML_PWR_BLUE_LED_R")
			(options
				(clearance outline)
				(anchor circle)
			)
			(primitives
				(gr_poly
					(pts
						(arc
							(start -0.1778 -0.2794)
							(mid -0.249642 -0.249642)
							(end -0.2794 -0.1778)
						)
						(arc
							(start -0.2794 0.1778)
							(mid -0.249642 0.249642)
							(end -0.1778 0.2794)
						)
						(arc
							(start 0.1778 0.2794)
							(mid 0.249642 0.249642)
							(end 0.2794 0.1778)
						)
						(arc
							(start 0.2794 -0.1778)
							(mid 0.249642 -0.249642)
							(end 0.1778 -0.2794)
						)
					)
					(width 0)
					(fill yes)
				)
			)
		)
		(pad "2" smd custom
			(at 0 0.4445)
			(size 0.1397 0.1397)
			(layers "F.Cu" "F.Mask" "F.Paste")
			(net "BMC_ML_PWR_BLUE_LED")
			(options
				(clearance outline)
				(anchor circle)
			)
			(primitives
				(gr_poly
					(pts
						(arc
							(start -0.1778 -0.2794)
							(mid -0.249642 -0.249642)
							(end -0.2794 -0.1778)
						)
						(arc
							(start -0.2794 0.1778)
							(mid -0.249642 0.249642)
							(end -0.1778 0.2794)
						)
						(arc
							(start 0.1778 0.2794)
							(mid 0.249642 0.249642)
							(end 0.2794 0.1778)
						)
						(arc
							(start 0.2794 -0.1778)
							(mid 0.249642 -0.249642)
							(end 0.1778 -0.2794)
						)
					)
					(width 0)
					(fill yes)
				)
			)
		)
	)
	(footprint ""
		(layer "F.Cu")
		(at 51.2064 -127.8382 90)
		(property "Reference" "R87"
			(at 0 0 90)
			(layer "F.SilkS")
			(hide yes)
			(effects
				(font
					(size 1.27 1.27)
				)
			)
		)
		(property "Value" "100KR2F-L1-GP"
			(at 0.064008 -3.993896 90)
			(unlocked yes)
			(layer "F.Fab")
			(hide yes)
			(effects
				(font
					(size 1.016 1.016)
					(thickness 0.1524)
				)
			)
		)
		(property "Device Type" "R402H16"
			(at 0.064008 -5.517896 90)
			(unlocked yes)
			(layer "F.Fab")
			(hide yes)
			(effects
				(font
					(size 1.016 1.016)
					(thickness 0.1524)
				)
			)
		)
		(duplicate_pad_numbers_are_jumpers no)
		(fp_line
			(start 0.508 -0.9398)
			(end -0.508 -0.9398)
			(stroke
				(width 0.1524)
				(type default)
			)
			(layer "F.SilkS")
		)
		(fp_line
			(start -0.508 -0.9398)
			(end -0.508 0.9398)
			(stroke
				(width 0.1524)
				(type default)
			)
			(layer "F.SilkS")
		)
		(fp_rect
			(start -0.508 0.9398)
			(end 0.508 -0.9398)
			(stroke
				(width 0)
				(type default)
			)
			(fill no)
			(layer "F.CrtYd")
		)
		(fp_rect
			(start -0.508 0.9398)
			(end 0.508 -0.9398)
			(stroke
				(width 0)
				(type default)
			)
			(fill no)
			(layer "F.Fab")
		)
		(pad "1" smd custom
			(at 0 -0.4445 90)
			(size 0.1397 0.1397)
			(layers "F.Cu" "F.Mask" "F.Paste")
			(net "SCC_RMT_FULL_PWR_EN")
			(options
				(clearance outline)
				(anchor circle)
			)
			(primitives
				(gr_poly
					(pts
						(arc
							(start -0.1778 -0.2794)
							(mid -0.249642 -0.249642)
							(end -0.2794 -0.1778)
						)
						(arc
							(start -0.2794 0.1778)
							(mid -0.249642 0.249642)
							(end -0.1778 0.2794)
						)
						(arc
							(start 0.1778 0.2794)
							(mid 0.249642 0.249642)
							(end 0.2794 0.1778)
						)
						(arc
							(start 0.2794 -0.1778)
							(mid 0.249642 -0.249642)
							(end 0.1778 -0.2794)
						)
					)
					(width 0)
					(fill yes)
				)
			)
		)
		(pad "2" smd custom
			(at 0 0.4445 90)
			(size 0.1397 0.1397)
			(layers "F.Cu" "F.Mask" "F.Paste")
			(net "GND")
			(options
				(clearance outline)
				(anchor circle)
			)
			(primitives
				(gr_poly
					(pts
						(arc
							(start -0.1778 -0.2794)
							(mid -0.249642 -0.249642)
							(end -0.2794 -0.1778)
						)
						(arc
							(start -0.2794 0.1778)
							(mid -0.249642 0.249642)
							(end -0.1778 0.2794)
						)
						(arc
							(start 0.1778 0.2794)
							(mid 0.249642 0.249642)
							(end 0.2794 0.1778)
						)
						(arc
							(start 0.2794 -0.1778)
							(mid 0.249642 -0.249642)
							(end 0.1778 -0.2794)
						)
					)
					(width 0)
					(fill yes)
				)
			)
		)
	)
)
